(kicad_pcb
	(version 20260206)
	(generator "pcbnew")
	(generator_version "10.0")
	(general
		(thickness 1.6)
		(legacy_teardrops no)
	)
	(paper "A4")
	(title_block
		(title "pdpb — Lightning_PDPB_BRD.brd")
		(comment 1 "Lightning (Wiwynn / Facebook NVMe JBOF) / footprints 437-443 of 1140")
	)
	(layers
		(0 "F.Cu" signal "TOP")
		(4 "In1.Cu" signal "L2GND")
		(6 "In2.Cu" signal "L3")
		(8 "In3.Cu" signal "L4VCC")
		(10 "In4.Cu" signal "L5VCC")
		(12 "In5.Cu" signal "L6")
		(14 "In6.Cu" signal "L7GND")
		(2 "B.Cu" signal "BOTTOM")
		(9 "F.Adhes" user "F.Adhesive")
		(11 "B.Adhes" user "B.Adhesive")
		(13 "F.Paste" user "Package Geometry/Pastemask Top")
		(15 "B.Paste" user "Package Geometry/Pastemask Bottom")
		(5 "F.SilkS" user "Ref Des/Silkscreen Top")
		(7 "B.SilkS" user "Ref Des/Silkscreen Bottom")
		(1 "F.Mask" user "Board Geometry/Soldermask Top")
		(3 "B.Mask" user "Board Geometry/Soldermask Bottom")
		(17 "Dwgs.User" user "User.Drawings")
		(19 "Cmts.User" user "User.Comments")
		(21 "Eco1.User" user "User.Eco1")
		(23 "Eco2.User" user "User.Eco2")
		(25 "Edge.Cuts" user "Board Geometry/Outline")
		(27 "Margin" user)
		(31 "F.CrtYd" user "Package Geometry/Place Bound Top")
		(29 "B.CrtYd" user "Package Geometry/Place Bound Bottom")
		(35 "F.Fab" user "Ref Des/Assembly Top")
		(33 "B.Fab" user "Ref Des/Assembly Bottom")
	)
	(footprint ""
		(layer "F.Cu")
		(at 203.454 -50.292 90)
		(property "Reference" "R326"
			(at 0 0 90)
			(layer "F.SilkS")
			(hide yes)
			(effects
				(font
					(size 1.27 1.27)
				)
			)
		)
		(property "Value" "0R2J-2-GP"
			(at 0.064008 -3.993896 90)
			(unlocked yes)
			(layer "F.Fab")
			(hide yes)
			(effects
				(font
					(size 1.016 1.016)
					(thickness 0.1524)
				)
			)
		)
		(property "Device Type" "R402H16"
			(at 0.064008 -5.517896 90)
			(unlocked yes)
			(layer "F.Fab")
			(hide yes)
			(effects
				(font
					(size 1.016 1.016)
					(thickness 0.1524)
				)
			)
		)
		(duplicate_pad_numbers_are_jumpers no)
		(fp_line
			(start 0.508 -0.9398)
			(end -0.508 -0.9398)
			(stroke
				(width 0.1524)
				(type default)
			)
			(layer "F.SilkS")
		)
		(fp_line
			(start -0.508 -0.9398)
			(end -0.508 0.9398)
			(stroke
				(width 0.1524)
				(type default)
			)
			(layer "F.SilkS")
		)
		(fp_rect
			(start -0.508 0.9398)
			(end 0.508 -0.9398)
			(stroke
				(width 0)
				(type default)
			)
			(fill no)
			(layer "F.CrtYd")
		)
		(fp_rect
			(start -0.508 0.9398)
			(end 0.508 -0.9398)
			(stroke
				(width 0)
				(type default)
			)
			(fill no)
			(layer "F.Fab")
		)
		(pad "1" smd custom
			(at 0 -0.4445 90)
			(size 0.1397 0.1397)
			(layers "F.Cu" "F.Mask" "F.Paste")
			(net "I2C_B_SDA")
			(options
				(clearance outline)
				(anchor circle)
			)
			(primitives
				(gr_poly
					(pts
						(arc
							(start -0.1778 -0.2794)
							(mid -0.249642 -0.249642)
							(end -0.2794 -0.1778)
						)
						(arc
							(start -0.2794 0.1778)
							(mid -0.249642 0.249642)
							(end -0.1778 0.2794)
						)
						(arc
							(start 0.1778 0.2794)
							(mid 0.249642 0.249642)
							(end 0.2794 0.1778)
						)
						(arc
							(start 0.2794 -0.1778)
							(mid 0.249642 -0.249642)
							(end 0.1778 -0.2794)
						)
					)
					(width 0)
					(fill yes)
				)
			)
		)
		(pad "2" smd custom
			(at 0 0.4445 90)
			(size 0.1397 0.1397)
			(layers "F.Cu" "F.Mask" "F.Paste")
			(net "TMP3_SDA")
			(options
				(clearance outline)
				(anchor circle)
			)
			(primitives
				(gr_poly
					(pts
						(arc
							(start -0.1778 -0.2794)
							(mid -0.249642 -0.249642)
							(end -0.2794 -0.1778)
						)
						(arc
							(start -0.2794 0.1778)
							(mid -0.249642 0.249642)
							(end -0.1778 0.2794)
						)
						(arc
							(start 0.1778 0.2794)
							(mid 0.249642 0.249642)
							(end 0.2794 0.1778)
						)
						(arc
							(start 0.2794 -0.1778)
							(mid 0.249642 -0.249642)
							(end 0.1778 -0.2794)
						)
					)
					(width 0)
					(fill yes)
				)
			)
		)
	)
	(footprint ""
		(layer "F.Cu")
		(at 24.003 -157.474158 -90)
		(property "Reference" "SR1147"
			(at 0 0 270)
			(layer "F.SilkS")
			(hide yes)
			(effects
				(font
					(size 1.27 1.27)
				)
			)
		)
		(property "Value" "4K7R2F-GP"
			(at 0.064008 -3.993896 270)
			(unlocked yes)
			(layer "F.Fab")
			(hide yes)
			(effects
				(font
					(size 1.016 1.016)
					(thickness 0.1524)
				)
			)
		)
		(property "Device Type" "R402H16"
			(at 0.064008 -5.517896 270)
			(unlocked yes)
			(layer "F.Fab")
			(hide yes)
			(effects
				(font
					(size 1.016 1.016)
					(thickness 0.1524)
				)
			)
		)
		(duplicate_pad_numbers_are_jumpers no)
		(fp_line
			(start -0.508 -0.9398)
			(end -0.508 0.9398)
			(stroke
				(width 0.1524)
				(type default)
			)
			(layer "F.SilkS")
		)
		(fp_line
			(start 0.508 -0.9398)
			(end -0.508 -0.9398)
			(stroke
				(width 0.1524)
				(type default)
			)
			(layer "F.SilkS")
		)
		(fp_rect
			(start -0.508 0.9398)
			(end 0.508 -0.9398)
			(stroke
				(width 0)
				(type default)
			)
			(fill no)
			(layer "F.CrtYd")
		)
		(fp_rect
			(start -0.508 0.9398)
			(end 0.508 -0.9398)
			(stroke
				(width 0)
				(type default)
			)
			(fill no)
			(layer "F.Fab")
		)
		(pad "1" smd custom
			(at 0 -0.4445 270)
			(size 0.1397 0.1397)
			(layers "F.Cu" "F.Mask" "F.Paste")
			(net "P3V3")
			(options
				(clearance outline)
				(anchor circle)
			)
			(primitives
				(gr_poly
					(pts
						(arc
							(start -0.1778 -0.2794)
							(mid -0.249642 -0.249642)
							(end -0.2794 -0.1778)
						)
						(arc
							(start -0.2794 0.1778)
							(mid -0.249642 0.249642)
							(end -0.1778 0.2794)
						)
						(arc
							(start 0.1778 0.2794)
							(mid 0.249642 0.249642)
							(end 0.2794 0.1778)
						)
						(arc
							(start 0.2794 -0.1778)
							(mid 0.249642 -0.249642)
							(end 0.1778 -0.2794)
						)
					)
					(width 0)
					(fill yes)
				)
			)
		)
		(pad "2" smd custom
			(at 0 0.4445 270)
			(size 0.1397 0.1397)
			(layers "F.Cu" "F.Mask" "F.Paste")
			(net "SSD13_CLK0_OE_MOS_N")
			(options
				(clearance outline)
				(anchor circle)
			)
			(primitives
				(gr_poly
					(pts
						(arc
							(start -0.1778 -0.2794)
							(mid -0.249642 -0.249642)
							(end -0.2794 -0.1778)
						)
						(arc
							(start -0.2794 0.1778)
							(mid -0.249642 0.249642)
							(end -0.1778 0.2794)
						)
						(arc
							(start 0.1778 0.2794)
							(mid 0.249642 0.249642)
							(end 0.2794 0.1778)
						)
						(arc
							(start 0.2794 -0.1778)
							(mid 0.249642 -0.249642)
							(end 0.1778 -0.2794)
						)
					)
					(width 0)
					(fill yes)
				)
			)
		)
	)
	(footprint ""
		(layer "F.Cu")
		(at 94.615 -439.293 180)
		(property "Reference" "C8839"
			(at 0 0 180)
			(layer "F.SilkS")
			(hide yes)
			(effects
				(font
					(size 1.27 1.27)
				)
			)
		)
		(property "Value" "SCD1U16V2KX-3GP"
			(at 1.1811 -2.7051 180)
			(unlocked yes)
			(layer "F.Fab")
			(hide yes)
			(effects
				(font
					(size 1.016 1.016)
					(thickness 0.1524)
				)
			)
		)
		(property "Device Type" "C402H22"
			(at 1.1811 -4.2291 180)
			(unlocked yes)
			(layer "F.Fab")
			(hide yes)
			(effects
				(font
					(size 1.016 1.016)
					(thickness 0.1524)
				)
			)
		)
		(duplicate_pad_numbers_are_jumpers no)
		(fp_rect
			(start -0.4318 0.9525)
			(end 0.4318 -0.9525)
			(stroke
				(width 0)
				(type default)
			)
			(fill no)
			(layer "F.CrtYd")
		)
		(fp_rect
			(start -0.4318 0.9525)
			(end 0.4318 -0.9525)
			(stroke
				(width 0)
				(type default)
			)
			(fill no)
			(layer "F.Fab")
		)
		(pad "1" smd custom
			(at 0 -0.4445 180)
			(size 0.1524 0.1524)
			(layers "F.Cu" "F.Mask" "F.Paste")
			(net "VDD_IO_1")
			(options
				(clearance outline)
				(anchor circle)
			)
			(primitives
				(gr_poly
					(pts
						(arc
							(start 0.3048 -0.2032)
							(mid 0.275042 -0.275042)
							(end 0.2032 -0.3048)
						)
						(arc
							(start -0.2032 -0.3048)
							(mid -0.275042 -0.275042)
							(end -0.3048 -0.2032)
						)
						(arc
							(start -0.3048 0.2032)
							(mid -0.275042 0.275042)
							(end -0.2032 0.3048)
						)
						(arc
							(start 0.2032 0.3048)
							(mid 0.275042 0.275042)
							(end 0.3048 0.2032)
						)
					)
					(width 0)
					(fill yes)
				)
			)
		)
		(pad "2" smd custom
			(at 0 0.4445 180)
			(size 0.1524 0.1524)
			(layers "F.Cu" "F.Mask" "F.Paste")
			(net "GND")
			(options
				(clearance outline)
				(anchor circle)
			)
			(primitives
				(gr_poly
					(pts
						(arc
							(start 0.3048 -0.2032)
							(mid 0.275042 -0.275042)
							(end 0.2032 -0.3048)
						)
						(arc
							(start -0.2032 -0.3048)
							(mid -0.275042 -0.275042)
							(end -0.3048 -0.2032)
						)
						(arc
							(start -0.3048 0.2032)
							(mid -0.275042 0.275042)
							(end -0.2032 0.3048)
						)
						(arc
							(start 0.2032 0.3048)
							(mid 0.275042 0.275042)
							(end 0.3048 0.2032)
						)
					)
					(width 0)
					(fill yes)
				)
			)
		)
	)
	(footprint ""
		(layer "F.Cu")
		(at 8.8138 -473.7608 90)
		(property "Reference" "PC1096"
			(at 0 0 90)
			(layer "F.SilkS")
			(hide yes)
			(effects
				(font
					(size 1.27 1.27)
				)
			)
		)
		(property "Value" "SC22U25V6KX-GP-U"
			(at -2.860802 -5.279644 90)
			(unlocked yes)
			(layer "F.Fab")
			(hide yes)
			(effects
				(font
					(size 1.016 1.016)
					(thickness 0.1524)
				)
			)
		)
		(property "Device Type" "C1206-TO0D3H75"
			(at -2.860802 -6.803644 90)
			(unlocked yes)
			(layer "F.Fab")
			(hide yes)
			(effects
				(font
					(size 1.016 1.016)
					(thickness 0.1524)
				)
			)
		)
		(duplicate_pad_numbers_are_jumpers no)
		(fp_line
			(start 1.3081 -2.3749)
			(end 1.3081 2.3749)
			(stroke
				(width 0.1524)
				(type default)
			)
			(layer "F.SilkS")
		)
		(fp_line
			(start -1.3081 -2.3749)
			(end 1.3081 -2.3749)
			(stroke
				(width 0.1524)
				(type default)
			)
			(layer "F.SilkS")
		)
		(fp_line
			(start 1.3081 2.3749)
			(end -1.3081 2.3749)
			(stroke
				(width 0.1524)
				(type default)
			)
			(layer "F.SilkS")
		)
		(fp_line
			(start -1.3081 2.3749)
			(end -1.3081 -2.3749)
			(stroke
				(width 0.1524)
				(type default)
			)
			(layer "F.SilkS")
		)
		(fp_rect
			(start -0.8001 1.6002)
			(end 0.8001 -1.6002)
			(stroke
				(width 0)
				(type default)
			)
			(fill no)
			(layer "F.CrtYd")
		)
		(fp_poly
			(pts
				(xy -1.5621 2.4511) (xy -1.5621 1.6002) (xy 0.8001 1.6002) (xy 0.8001 -1.6002) (xy -0.8001 -1.6002)
				(xy -0.8001 1.5875) (xy -1.5621 1.5875) (xy -1.5621 -2.4511) (xy 1.5621 -2.4511) (xy 1.5621 2.4511)
			)
			(stroke
				(width 0)
				(type default)
			)
			(fill no)
			(layer "F.CrtYd")
		)
		(fp_rect
			(start -1.5621 2.4511)
			(end 1.5621 -2.4511)
			(stroke
				(width 0)
				(type default)
			)
			(fill no)
			(layer "F.Fab")
		)
		(pad "1" smd rect
			(at 0 -1.392936 90)
			(size 2.1082 1.4478)
			(layers "F.Cu" "F.Mask" "F.Paste")
			(net "P12V")
		)
		(pad "2" smd rect
			(at 0 1.392936 90)
			(size 2.1082 1.4478)
			(layers "F.Cu" "F.Mask" "F.Paste")
			(net "GND")
		)
	)
	(footprint ""
		(layer "F.Cu")
		(at 81.661 -360.045 -90)
		(property "Reference" "SR990"
			(at 0 0 270)
			(layer "F.SilkS")
			(hide yes)
			(effects
				(font
					(size 1.27 1.27)
				)
			)
		)
		(property "Value" "2KR2F-3-GP"
			(at 0.064008 -3.993896 270)
			(unlocked yes)
			(layer "F.Fab")
			(hide yes)
			(effects
				(font
					(size 1.016 1.016)
					(thickness 0.1524)
				)
			)
		)
		(property "Device Type" "R402H16"
			(at 0.064008 -5.517896 270)
			(unlocked yes)
			(layer "F.Fab")
			(hide yes)
			(effects
				(font
					(size 1.016 1.016)
					(thickness 0.1524)
				)
			)
		)
		(duplicate_pad_numbers_are_jumpers no)
		(fp_line
			(start -0.508 -0.9398)
			(end -0.508 0.9398)
			(stroke
				(width 0.1524)
				(type default)
			)
			(layer "F.SilkS")
		)
		(fp_line
			(start 0.508 -0.9398)
			(end -0.508 -0.9398)
			(stroke
				(width 0.1524)
				(type default)
			)
			(layer "F.SilkS")
		)
		(fp_rect
			(start -0.508 0.9398)
			(end 0.508 -0.9398)
			(stroke
				(width 0)
				(type default)
			)
			(fill no)
			(layer "F.CrtYd")
		)
		(fp_rect
			(start -0.508 0.9398)
			(end 0.508 -0.9398)
			(stroke
				(width 0)
				(type default)
			)
			(fill no)
			(layer "F.Fab")
		)
		(pad "1" smd custom
			(at 0 -0.4445 270)
			(size 0.1397 0.1397)
			(layers "F.Cu" "F.Mask" "F.Paste")
			(net "P3V3")
			(options
				(clearance outline)
				(anchor circle)
			)
			(primitives
				(gr_poly
					(pts
						(arc
							(start -0.1778 -0.2794)
							(mid -0.249642 -0.249642)
							(end -0.2794 -0.1778)
						)
						(arc
							(start -0.2794 0.1778)
							(mid -0.249642 0.249642)
							(end -0.1778 0.2794)
						)
						(arc
							(start 0.1778 0.2794)
							(mid 0.249642 0.249642)
							(end 0.2794 0.1778)
						)
						(arc
							(start 0.2794 -0.1778)
							(mid 0.249642 -0.249642)
							(end 0.1778 -0.2794)
						)
					)
					(width 0)
					(fill yes)
				)
			)
		)
		(pad "2" smd custom
			(at 0 0.4445 270)
			(size 0.1397 0.1397)
			(layers "F.Cu" "F.Mask" "F.Paste")
			(net "SDA_DR1")
			(options
				(clearance outline)
				(anchor circle)
			)
			(primitives
				(gr_poly
					(pts
						(arc
							(start -0.1778 -0.2794)
							(mid -0.249642 -0.249642)
							(end -0.2794 -0.1778)
						)
						(arc
							(start -0.2794 0.1778)
							(mid -0.249642 0.249642)
							(end -0.1778 0.2794)
						)
						(arc
							(start 0.1778 0.2794)
							(mid 0.249642 0.249642)
							(end 0.2794 0.1778)
						)
						(arc
							(start 0.2794 -0.1778)
							(mid 0.249642 -0.249642)
							(end 0.1778 -0.2794)
						)
					)
					(width 0)
					(fill yes)
				)
			)
		)
	)
	(footprint ""
		(layer "F.Cu")
		(at 210.312 -190.119)
		(property "Reference" "C385"
			(at 0 0 0)
			(layer "F.SilkS")
			(hide yes)
			(effects
				(font
					(size 1.27 1.27)
				)
			)
		)
		(property "Value" "SCD1U25V2KX-2-GP"
			(at 1.1811 -2.7051 0)
			(unlocked yes)
			(layer "F.Fab")
			(hide yes)
			(effects
				(font
					(size 1.016 1.016)
					(thickness 0.1524)
				)
			)
		)
		(property "Device Type" "C402H22"
			(at 1.1811 -4.2291 0)
			(unlocked yes)
			(layer "F.Fab")
			(hide yes)
			(effects
				(font
					(size 1.016 1.016)
					(thickness 0.1524)
				)
			)
		)
		(duplicate_pad_numbers_are_jumpers no)
		(fp_rect
			(start -0.4318 0.9525)
			(end 0.4318 -0.9525)
			(stroke
				(width 0)
				(type default)
			)
			(fill no)
			(layer "F.CrtYd")
		)
		(fp_rect
			(start -0.4318 0.9525)
			(end 0.4318 -0.9525)
			(stroke
				(width 0)
				(type default)
			)
			(fill no)
			(layer "F.Fab")
		)
		(pad "1" smd custom
			(at 0 -0.4445)
			(size 0.1524 0.1524)
			(layers "F.Cu" "F.Mask" "F.Paste")
			(net "P12V")
			(options
				(clearance outline)
				(anchor circle)
			)
			(primitives
				(gr_poly
					(pts
						(arc
							(start 0.3048 -0.2032)
							(mid 0.275042 -0.275042)
							(end 0.2032 -0.3048)
						)
						(arc
							(start -0.2032 -0.3048)
							(mid -0.275042 -0.275042)
							(end -0.3048 -0.2032)
						)
						(arc
							(start -0.3048 0.2032)
							(mid -0.275042 0.275042)
							(end -0.2032 0.3048)
						)
						(arc
							(start 0.2032 0.3048)
							(mid 0.275042 0.275042)
							(end 0.3048 0.2032)
						)
					)
					(width 0)
					(fill yes)
				)
			)
		)
		(pad "2" smd custom
			(at 0 0.4445)
			(size 0.1524 0.1524)
			(layers "F.Cu" "F.Mask" "F.Paste")
			(net "SW_SSD3_N")
			(options
				(clearance outline)
				(anchor circle)
			)
			(primitives
				(gr_poly
					(pts
						(arc
							(start 0.3048 -0.2032)
							(mid 0.275042 -0.275042)
							(end 0.2032 -0.3048)
						)
						(arc
							(start -0.2032 -0.3048)
							(mid -0.275042 -0.275042)
							(end -0.3048 -0.2032)
						)
						(arc
							(start -0.3048 0.2032)
							(mid -0.275042 0.275042)
							(end -0.2032 0.3048)
						)
						(arc
							(start 0.2032 0.3048)
							(mid 0.275042 0.275042)
							(end 0.3048 0.2032)
						)
					)
					(width 0)
					(fill yes)
				)
			)
		)
	)
	(footprint ""
		(layer "F.Cu")
		(at 20.066 -373.38 -90)
		(property "Reference" "R9853"
			(at 0 0 270)
			(layer "F.SilkS")
			(hide yes)
			(effects
				(font
					(size 1.27 1.27)
				)
			)
		)
		(property "Value" "0R2J-2-GP"
			(at 0.064008 -3.993896 270)
			(unlocked yes)
			(layer "F.Fab")
			(hide yes)
			(effects
				(font
					(size 1.016 1.016)
					(thickness 0.1524)
				)
			)
		)
		(property "Device Type" "R402H16"
			(at 0.064008 -5.517896 270)
			(unlocked yes)
			(layer "F.Fab")
			(hide yes)
			(effects
				(font
					(size 1.016 1.016)
					(thickness 0.1524)
				)
			)
		)
		(duplicate_pad_numbers_are_jumpers no)
		(fp_line
			(start -0.508 -0.9398)
			(end -0.508 0.9398)
			(stroke
				(width 0.1524)
				(type default)
			)
			(layer "F.SilkS")
		)
		(fp_line
			(start 0.508 -0.9398)
			(end -0.508 -0.9398)
			(stroke
				(width 0.1524)
				(type default)
			)
			(layer "F.SilkS")
		)
		(fp_rect
			(start -0.508 0.9398)
			(end 0.508 -0.9398)
			(stroke
				(width 0)
				(type default)
			)
			(fill no)
			(layer "F.CrtYd")
		)
		(fp_rect
			(start -0.508 0.9398)
			(end 0.508 -0.9398)
			(stroke
				(width 0)
				(type default)
			)
			(fill no)
			(layer "F.Fab")
		)
		(pad "1" smd custom
			(at 0 -0.4445 270)
			(size 0.1397 0.1397)
			(layers "F.Cu" "F.Mask" "F.Paste")
			(net "ATTN_LED_DR11_AND")
			(options
				(clearance outline)
				(anchor circle)
			)
			(primitives
				(gr_poly
					(pts
						(arc
							(start -0.1778 -0.2794)
							(mid -0.249642 -0.249642)
							(end -0.2794 -0.1778)
						)
						(arc
							(start -0.2794 0.1778)
							(mid -0.249642 0.249642)
							(end -0.1778 0.2794)
						)
						(arc
							(start 0.1778 0.2794)
							(mid 0.249642 0.249642)
							(end 0.2794 0.1778)
						)
						(arc
							(start 0.2794 -0.1778)
							(mid 0.249642 -0.249642)
							(end 0.1778 -0.2794)
						)
					)
					(width 0)
					(fill yes)
				)
			)
		)
		(pad "2" smd custom
			(at 0 0.4445 270)
			(size 0.1397 0.1397)
			(layers "F.Cu" "F.Mask" "F.Paste")
			(net "ATTN_LED_DR11_AND_R")
			(options
				(clearance outline)
				(anchor circle)
			)
			(primitives
				(gr_poly
					(pts
						(arc
							(start -0.1778 -0.2794)
							(mid -0.249642 -0.249642)
							(end -0.2794 -0.1778)
						)
						(arc
							(start -0.2794 0.1778)
							(mid -0.249642 0.249642)
							(end -0.1778 0.2794)
						)
						(arc
							(start 0.1778 0.2794)
							(mid 0.249642 0.249642)
							(end 0.2794 0.1778)
						)
						(arc
							(start 0.2794 -0.1778)
							(mid 0.249642 -0.249642)
							(end 0.1778 -0.2794)
						)
					)
					(width 0)
					(fill yes)
				)
			)
		)
	)
)
